# T6G (Grand Teton) — schematic netlist excerpt (pin names and nets, part order shuffled) for the footprints in the layout excerpt that follows; sources: Cadence DE-HDL packaged netlist, KiCad conversion of 04192023_DAF0TMB3IC0_F0TG_MB_C_brd_V02_OCP.brd

PU25  RAA229620GNPHA0  RAA229620GNP#HA0 IC  pkg QFN48_TH_0-4_6X6XH  page 210
  PWM0  = PVDDCR_SOC_P1_PWM1
  PWM1  = PVDDCR_SOC_P1_PWM2
  PWM2  = PVDDCR_SOC_P1_PWM3
  PWM3  = NC_PVDDCR_CPU0_P1_PWM9
  PWM4  = NC_PVDDCR_CPU0_P1_PWM8
  PWM5  = NC_PVDDCR_CPU0_P1_PWM7
  PWM6  = PVDDCR_CPU0_P1_PWM6
  PWM7  = PVDDCR_CPU0_P1_PWM5
  PWM8  = PVDDCR_CPU0_P1_PWM4
  PWM9  = PVDDCR_CPU0_P1_PWM3
  PWM10  = PVDDCR_CPU0_P1_PWM2
  PWM11  = PVDDCR_CPU0_P1_PWM1
  PMSDA  = PVDDCR_CPU0_P1_PMSDA_R
  PMSCL  = PVDDCR_CPU0_P1_PMSCL_R
  NPMALERT  = PVDDCR_CPU0_P1_PMALERT_R
  PG0  = PWRGD_PVDDCR_CPU0_P1_R
  EN0  = PVDDCR_CPU0_P1_EN_R
  RESET_L  = PVDDCR_CPU0_P1_RESET_N_R
  VDDIO  = PVDD18_S5_P1
  PG1  = PWRGD_PVDDCR_SOC_P1_R
  SVD  = SVID_PVDDCR_CPU0_P1_SVD_R1
  SVC  = SVID_PVDDCR_CPU0_P1_SVC_R1
  SVTO  = SVID_PVDDCR_CPU0_P1_SVTO_R
  SVTI  = SVID_PVDDCR_CPU0_P1_SVTI_R
  VSEN0  = VSENSE_PVDDCR_CPU0_P1_VSEN0
  RGND0  = VSENSE_VSS_SENSE_A_P1
  CS11  = PVDDCR_CPU0_P1_IMON1
  CS10  = PVDDCR_CPU0_P1_IMON2
  CS9  = PVDDCR_CPU0_P1_IMON3
  CS8  = PVDDCR_CPU0_P1_IMON4
  CS7  = PVDDCR_CPU0_P1_IMON5
  CS6  = PVDDCR_CPU0_P1_IMON6
  CS5  = NC_PVDDCR_CPU0_P1_IMON7
  CS4  = NC_PVDDCR_CPU0_P1_IMON8
  CS3  = NC_PVDDCR_CPU0_P1_IMON9
  CS2  = PVDDCR_SOC_P1_IMON3
  CS1  = PVDDCR_SOC_P1_IMON2
  CS0  = PVDDCR_SOC_P1_IMON1
  RGND1  = VSENSE_VSS_SENSE_A_P1
  VSEN1  = VSENSE_PVDDCR_SOC_P1_VSEN1
  OCP_L  = PVDDCR_CPU0_P1_OCP_N_R
  \en1||addr_cfg\  = PVDDCR_SOC_P1_EN//ADDR_CFG
  TEMP1  = PVDDCR_SOC_P1_TEMP1
  TEMP0  = PVDDCR_CPU0_P1_TEMP0
  \vmon||iinsen\  = PVDDCR_CPU0_P1_VMON
  VINSEN  = PVDDCR_CPU0_P1_VINSEN
  VCC  = PVDDCR_CPU0_P1_VCC
  VCCS  = PVDDCR_CPU0_P1_VCCS
  TH_GND  = GND

(kicad_pcb
	(version 20260206)
	(generator "pcbnew")
	(generator_version "10.0")
	(general
		(thickness 1.6)
		(legacy_teardrops no)
	)
	(paper "A4")
	(title_block
		(title "04192023_DAF0TMB3IC0_F0TG_MB_C_brd_V02_OCP.brd")
		(comment 1 "Grand Teton / footprint 6057 of 8354 (PU25), pads 42-49 of 49")
	)
	(layers
		(0 "F.Cu" signal "TOP")
		(4 "In1.Cu" signal "GND")
		(6 "In2.Cu" signal "IN1")
		(8 "In3.Cu" signal "GND1")
		(10 "In4.Cu" signal "IN2")
		(12 "In5.Cu" signal "GND2")
		(14 "In6.Cu" signal "IN3")
		(16 "In7.Cu" signal "GND3")
		(18 "In8.Cu" signal "VCC")
		(20 "In9.Cu" signal "VCC1")
		(22 "In10.Cu" signal "GND4")
		(24 "In11.Cu" signal "IN4")
		(26 "In12.Cu" signal "GND5")
		(28 "In13.Cu" signal "IN5")
		(30 "In14.Cu" signal "GND6")
		(32 "In15.Cu" signal "IN6")
		(34 "In16.Cu" signal "GND7")
		(2 "B.Cu" signal "BOTTOM")
		(9 "F.Adhes" user "F.Adhesive")
		(11 "B.Adhes" user "B.Adhesive")
		(13 "F.Paste" user "Package Geometry/Pastemask Top")
		(15 "B.Paste" user "Package Geometry/Pastemask Bottom")
		(5 "F.SilkS" user "Ref Des/Silkscreen Top")
		(7 "B.SilkS" user "Ref Des/Silkscreen Bottom")
		(1 "F.Mask" user "Board Geometry/Soldermask Top")
		(3 "B.Mask" user "Board Geometry/Soldermask Bottom")
		(17 "Dwgs.User" user "User.Drawings")
		(19 "Cmts.User" user "User.Comments")
		(21 "Eco1.User" user "User.Eco1")
		(23 "Eco2.User" user "User.Eco2")
		(25 "Edge.Cuts" user "Board Geometry/Outline")
		(27 "Margin" user)
		(31 "F.CrtYd" user "Package Geometry/Place Bound Top")
		(29 "B.CrtYd" user "Package Geometry/Place Bound Bottom")
		(35 "F.Fab" user "Ref Des/Assembly Top")
		(33 "B.Fab" user "Ref Des/Assembly Bottom")
	)
	(footprint ""
		(layer "B.Cu")
		(at 95.670878 -144.75841 -90)
		(property "Reference" "PU25"
			(at -3.958844 -4.823714 0)
			(unlocked yes)
			(layer "B.SilkS")
			(effects
				(font
					(size 0.7874 0.5842)
					(thickness 0.1524)
				)
				(justify mirror)
			)
		)
		(property "Value" ""
			(at 0 0 90)
			(layer "B.Fab")
			(effects
				(font
					(size 1.27 1.27)
				)
				(justify mirror)
			)
		)
		(duplicate_pad_numbers_are_jumpers no)
		(pad "42" smd rect
			(at -0.199898 -2.875026 90)
			(size 0.1778 0.6604)
			(layers "B.Cu" "B.Mask" "B.Paste")
			(net "PVDDCR_SOC_P1_EN//ADDR_CFG")
		)
		(pad "43" smd rect
			(at 0.199898 -2.875026 90)
			(size 0.1778 0.6604)
			(layers "B.Cu" "B.Mask" "B.Paste")
			(net "PVDDCR_SOC_P1_TEMP1")
		)
		(pad "44" smd rect
			(at 0.599948 -2.875026 90)
			(size 0.1778 0.6604)
			(layers "B.Cu" "B.Mask" "B.Paste")
			(net "PVDDCR_CPU0_P1_TEMP0")
		)
		(pad "45" smd rect
			(at 0.999998 -2.875026 90)
			(size 0.1778 0.6604)
			(layers "B.Cu" "B.Mask" "B.Paste")
			(net "PVDDCR_CPU0_P1_VMON")
		)
		(pad "46" smd rect
			(at 1.400048 -2.875026 90)
			(size 0.1778 0.6604)
			(layers "B.Cu" "B.Mask" "B.Paste")
			(net "PVDDCR_CPU0_P1_VINSEN")
		)
		(pad "47" smd rect
			(at 1.800098 -2.875026 90)
			(size 0.1778 0.6604)
			(layers "B.Cu" "B.Mask" "B.Paste")
			(net "PVDDCR_CPU0_P1_VCC")
		)
		(pad "48" smd rect
			(at 2.199894 -2.875026 90)
			(size 0.1778 0.6604)
			(layers "B.Cu" "B.Mask" "B.Paste")
			(net "PVDDCR_CPU0_P1_VCCS")
		)
		(pad "TH" smd rect
			(at 0 0 90)
			(size 4.4196 4.4196)
			(layers "B.Cu" "B.Mask" "B.Paste")
			(net "GND")
		)
	)
)
